(kicad_pcb
	(version 20260206)
	(generator "pcbnew")
	(generator_version "10.0")
	(general
		(thickness 1.6)
		(legacy_teardrops no)
	)
	(paper "A4")
	(title_block
		(title "Bryce Canyon_R.DPB_16317-1_OCP.brd")
		(comment 1 "Bryce Canyon / footprints 40-46 of 2099")
	)
	(layers
		(0 "F.Cu" signal "TOP")
		(4 "In1.Cu" signal "L2GND")
		(6 "In2.Cu" signal "L3")
		(8 "In3.Cu" signal "L4VCC")
		(10 "In4.Cu" signal "L5VCC")
		(12 "In5.Cu" signal "L6")
		(14 "In6.Cu" signal "L7GND")
		(2 "B.Cu" signal "BOTTOM")
		(9 "F.Adhes" user "F.Adhesive")
		(11 "B.Adhes" user "B.Adhesive")
		(13 "F.Paste" user "Package Geometry/Pastemask Top")
		(15 "B.Paste" user "Package Geometry/Pastemask Bottom")
		(5 "F.SilkS" user "Ref Des/Silkscreen Top")
		(7 "B.SilkS" user "Ref Des/Silkscreen Bottom")
		(1 "F.Mask" user "Board Geometry/Soldermask Top")
		(3 "B.Mask" user "Board Geometry/Soldermask Bottom")
		(17 "Dwgs.User" user "User.Drawings")
		(19 "Cmts.User" user "User.Comments")
		(21 "Eco1.User" user "User.Eco1")
		(23 "Eco2.User" user "User.Eco2")
		(25 "Edge.Cuts" user "Board Geometry/Outline")
		(27 "Margin" user)
		(31 "F.CrtYd" user "Package Geometry/Place Bound Top")
		(29 "B.CrtYd" user "Package Geometry/Place Bound Bottom")
		(35 "F.Fab" user "Ref Des/Assembly Top")
		(33 "B.Fab" user "Ref Des/Assembly Bottom")
	)
	(footprint ""
		(layer "F.Cu")
		(at 263.113774 -217.419936 -90)
		(property "Reference" "R119"
			(at 0 0 270)
			(layer "F.SilkS")
			(hide yes)
			(effects
				(font
					(size 1.27 1.27)
				)
			)
		)
		(property "Value" "4K7R2F-GP"
			(at 0.064008 -3.993896 270)
			(unlocked yes)
			(layer "F.Fab")
			(hide yes)
			(effects
				(font
					(size 1.016 1.016)
					(thickness 0.1524)
				)
			)
		)
		(property "Device Type" "R402H16"
			(at 0.064008 -5.517896 270)
			(unlocked yes)
			(layer "F.Fab")
			(hide yes)
			(effects
				(font
					(size 1.016 1.016)
					(thickness 0.1524)
				)
			)
		)
		(duplicate_pad_numbers_are_jumpers no)
		(fp_line
			(start -0.508 -0.9398)
			(end -0.508 0.9398)
			(stroke
				(width 0.1524)
				(type default)
			)
			(layer "F.SilkS")
		)
		(fp_line
			(start 0.508 -0.9398)
			(end -0.508 -0.9398)
			(stroke
				(width 0.1524)
				(type default)
			)
			(layer "F.SilkS")
		)
		(fp_rect
			(start -0.508 0.9398)
			(end 0.508 -0.9398)
			(stroke
				(width 0)
				(type default)
			)
			(fill no)
			(layer "F.CrtYd")
		)
		(fp_rect
			(start -0.508 0.9398)
			(end 0.508 -0.9398)
			(stroke
				(width 0)
				(type default)
			)
			(fill no)
			(layer "F.Fab")
		)
		(pad "1" smd custom
			(at 0 -0.4445 270)
			(size 0.1397 0.1397)
			(layers "F.Cu" "F.Mask" "F.Paste")
			(net "P3V3_STBY_B")
			(options
				(clearance outline)
				(anchor circle)
			)
			(primitives
				(gr_poly
					(pts
						(arc
							(start -0.1778 -0.2794)
							(mid -0.249642 -0.249642)
							(end -0.2794 -0.1778)
						)
						(arc
							(start -0.2794 0.1778)
							(mid -0.249642 0.249642)
							(end -0.1778 0.2794)
						)
						(arc
							(start 0.1778 0.2794)
							(mid 0.249642 0.249642)
							(end 0.2794 0.1778)
						)
						(arc
							(start 0.2794 -0.1778)
							(mid 0.249642 -0.249642)
							(end 0.1778 -0.2794)
						)
					)
					(width 0)
					(fill yes)
				)
			)
		)
		(pad "2" smd custom
			(at 0 0.4445 270)
			(size 0.1397 0.1397)
			(layers "F.Cu" "F.Mask" "F.Paste")
			(net "VOL_SEN_ADDR0")
			(options
				(clearance outline)
				(anchor circle)
			)
			(primitives
				(gr_poly
					(pts
						(arc
							(start -0.1778 -0.2794)
							(mid -0.249642 -0.249642)
							(end -0.2794 -0.1778)
						)
						(arc
							(start -0.2794 0.1778)
							(mid -0.249642 0.249642)
							(end -0.1778 0.2794)
						)
						(arc
							(start 0.1778 0.2794)
							(mid 0.249642 0.249642)
							(end 0.2794 0.1778)
						)
						(arc
							(start 0.2794 -0.1778)
							(mid 0.249642 -0.249642)
							(end 0.1778 -0.2794)
						)
					)
					(width 0)
					(fill yes)
				)
			)
		)
	)
	(footprint ""
		(layer "F.Cu")
		(at 400.431 -133.858 90)
		(property "Reference" "D20"
			(at 0 0 90)
			(layer "F.SilkS")
			(hide yes)
			(effects
				(font
					(size 1.27 1.27)
				)
			)
		)
		(property "Value" "RB551V30-GP"
			(at 0 -6.7818 90)
			(unlocked yes)
			(layer "F.Fab")
			(hide yes)
			(effects
				(font
					(size 1.016 1.016)
					(thickness 0.1524)
				)
			)
		)
		(property "Device Type" "SOD323AKH38"
			(at 0 -8.6868 90)
			(unlocked yes)
			(layer "F.Fab")
			(hide yes)
			(effects
				(font
					(size 1.016 1.016)
					(thickness 0.1524)
				)
			)
		)
		(duplicate_pad_numbers_are_jumpers no)
		(fp_line
			(start 0.889 -1.9304)
			(end 0.889 2.159)
			(stroke
				(width 0.1524)
				(type default)
			)
			(layer "F.SilkS")
		)
		(fp_line
			(start -0.889 -1.9304)
			(end 0.889 -1.9304)
			(stroke
				(width 0.1524)
				(type default)
			)
			(layer "F.SilkS")
		)
		(fp_line
			(start 0.762 2.0574)
			(end -0.762 2.0574)
			(stroke
				(width 0.508)
				(type default)
			)
			(layer "F.SilkS")
		)
		(fp_line
			(start 0.889 2.159)
			(end -0.889 2.159)
			(stroke
				(width 0.1524)
				(type default)
			)
			(layer "F.SilkS")
		)
		(fp_line
			(start -0.889 2.159)
			(end -0.889 -1.9304)
			(stroke
				(width 0.1524)
				(type default)
			)
			(layer "F.SilkS")
		)
		(fp_rect
			(start -1.016 2.3114)
			(end 1.016 -2.0066)
			(stroke
				(width 0)
				(type default)
			)
			(fill no)
			(layer "F.CrtYd")
		)
		(fp_poly
			(pts
				(xy -1.016 -2.0066) (xy 1.016 -2.0066) (xy 1.016 2.3114) (xy -1.016 2.3114)
			)
			(stroke
				(width 0)
				(type default)
			)
			(fill no)
			(layer "F.Fab")
		)
		(pad "A" smd rect
			(at 0 -1.143 90)
			(size 0.5588 1.016)
			(layers "F.Cu" "F.Mask" "F.Paste")
			(net "SW_HDD_R20")
		)
		(pad "K" smd rect
			(at 0 1.143 90)
			(size 0.5588 1.016)
			(layers "F.Cu" "F.Mask" "F.Paste")
			(net "SW_HDD_N20")
		)
	)
	(footprint ""
		(layer "F.Cu")
		(at 315.839348 -213.153752)
		(property "Reference" "R301"
			(at 0 0 0)
			(layer "F.SilkS")
			(hide yes)
			(effects
				(font
					(size 1.27 1.27)
				)
			)
		)
		(property "Value" "91R3F-1-GP"
			(at -0.0254 -2.5146 0)
			(unlocked yes)
			(layer "F.Fab")
			(hide yes)
			(effects
				(font
					(size 1.016 1.016)
					(thickness 0.1524)
				)
			)
		)
		(property "Device Type" "R603H22"
			(at -0.0254 -4.0386 0)
			(unlocked yes)
			(layer "F.Fab")
			(hide yes)
			(effects
				(font
					(size 1.016 1.016)
					(thickness 0.1524)
				)
			)
		)
		(duplicate_pad_numbers_are_jumpers no)
		(fp_line
			(start -0.4826 0)
			(end -0.2032 0)
			(stroke
				(width 0.2032)
				(type default)
			)
			(layer "F.SilkS")
		)
		(fp_line
			(start 0.2032 0)
			(end 0.4826 0)
			(stroke
				(width 0.2032)
				(type default)
			)
			(layer "F.SilkS")
		)
		(fp_rect
			(start -0.5842 1.3335)
			(end 0.5842 -1.3335)
			(stroke
				(width 0)
				(type default)
			)
			(fill no)
			(layer "F.CrtYd")
		)
		(fp_rect
			(start -0.5842 1.3335)
			(end 0.5842 -1.3335)
			(stroke
				(width 0)
				(type default)
			)
			(fill no)
			(layer "F.Fab")
		)
		(pad "1" smd custom
			(at 0 -0.762)
			(size 0.2159 0.2159)
			(layers "F.Cu" "F.Mask" "F.Paste")
			(net "P5V_B_3")
			(options
				(clearance outline)
				(anchor circle)
			)
			(primitives
				(gr_poly
					(pts
						(arc
							(start -0.3302 -0.4318)
							(mid -0.402042 -0.402042)
							(end -0.4318 -0.3302)
						)
						(arc
							(start -0.4318 0.3302)
							(mid -0.402042 0.402042)
							(end -0.3302 0.4318)
						)
						(arc
							(start 0.3302 0.4318)
							(mid 0.402042 0.402042)
							(end 0.4318 0.3302)
						)
						(arc
							(start 0.4318 -0.3302)
							(mid 0.402042 -0.402042)
							(end 0.3302 -0.4318)
						)
					)
					(width 0)
					(fill yes)
				)
			)
		)
		(pad "2" smd custom
			(at 0 0.762)
			(size 0.2159 0.2159)
			(layers "F.Cu" "F.Mask" "F.Paste")
			(net "DRV_ACT_6")
			(options
				(clearance outline)
				(anchor circle)
			)
			(primitives
				(gr_poly
					(pts
						(arc
							(start -0.3302 -0.4318)
							(mid -0.402042 -0.402042)
							(end -0.4318 -0.3302)
						)
						(arc
							(start -0.4318 0.3302)
							(mid -0.402042 0.402042)
							(end -0.3302 0.4318)
						)
						(arc
							(start 0.3302 0.4318)
							(mid 0.402042 0.402042)
							(end 0.4318 0.3302)
						)
						(arc
							(start 0.4318 -0.3302)
							(mid 0.402042 -0.402042)
							(end 0.3302 -0.4318)
						)
					)
					(width 0)
					(fill yes)
				)
			)
		)
	)
	(footprint ""
		(layer "F.Cu")
		(at 426.72 -243.586)
		(property "Reference" "R311"
			(at 0 0 0)
			(layer "F.SilkS")
			(hide yes)
			(effects
				(font
					(size 1.27 1.27)
				)
			)
		)
		(property "Value" "4K7R2F-GP"
			(at 0.064008 -3.993896 0)
			(unlocked yes)
			(layer "F.Fab")
			(hide yes)
			(effects
				(font
					(size 1.016 1.016)
					(thickness 0.1524)
				)
			)
		)
		(property "Device Type" "R402H16"
			(at 0.064008 -5.517896 0)
			(unlocked yes)
			(layer "F.Fab")
			(hide yes)
			(effects
				(font
					(size 1.016 1.016)
					(thickness 0.1524)
				)
			)
		)
		(duplicate_pad_numbers_are_jumpers no)
		(fp_line
			(start -0.508 -0.9398)
			(end -0.508 0.9398)
			(stroke
				(width 0.1524)
				(type default)
			)
			(layer "F.SilkS")
		)
		(fp_line
			(start 0.508 -0.9398)
			(end -0.508 -0.9398)
			(stroke
				(width 0.1524)
				(type default)
			)
			(layer "F.SilkS")
		)
		(fp_rect
			(start -0.508 0.9398)
			(end 0.508 -0.9398)
			(stroke
				(width 0)
				(type default)
			)
			(fill no)
			(layer "F.CrtYd")
		)
		(fp_rect
			(start -0.508 0.9398)
			(end 0.508 -0.9398)
			(stroke
				(width 0)
				(type default)
			)
			(fill no)
			(layer "F.Fab")
		)
		(pad "1" smd custom
			(at 0 -0.4445)
			(size 0.1397 0.1397)
			(layers "F.Cu" "F.Mask" "F.Paste")
			(net "SW_PWR_R_HDD9")
			(options
				(clearance outline)
				(anchor circle)
			)
			(primitives
				(gr_poly
					(pts
						(arc
							(start -0.1778 -0.2794)
							(mid -0.249642 -0.249642)
							(end -0.2794 -0.1778)
						)
						(arc
							(start -0.2794 0.1778)
							(mid -0.249642 0.249642)
							(end -0.1778 0.2794)
						)
						(arc
							(start 0.1778 0.2794)
							(mid 0.249642 0.249642)
							(end 0.2794 0.1778)
						)
						(arc
							(start 0.2794 -0.1778)
							(mid 0.249642 -0.249642)
							(end 0.1778 -0.2794)
						)
					)
					(width 0)
					(fill yes)
				)
			)
		)
		(pad "2" smd custom
			(at 0 0.4445)
			(size 0.1397 0.1397)
			(layers "F.Cu" "F.Mask" "F.Paste")
			(net "GND")
			(options
				(clearance outline)
				(anchor circle)
			)
			(primitives
				(gr_poly
					(pts
						(arc
							(start -0.1778 -0.2794)
							(mid -0.249642 -0.249642)
							(end -0.2794 -0.1778)
						)
						(arc
							(start -0.2794 0.1778)
							(mid -0.249642 0.249642)
							(end -0.1778 0.2794)
						)
						(arc
							(start 0.1778 0.2794)
							(mid 0.249642 0.249642)
							(end 0.2794 0.1778)
						)
						(arc
							(start 0.2794 -0.1778)
							(mid 0.249642 -0.249642)
							(end 0.1778 -0.2794)
						)
					)
					(width 0)
					(fill yes)
				)
			)
		)
	)
	(footprint ""
		(layer "F.Cu")
		(at 365.0234 -40.5892 -90)
		(property "Reference" "R784"
			(at 0 0 270)
			(layer "F.SilkS")
			(hide yes)
			(effects
				(font
					(size 1.27 1.27)
				)
			)
		)
		(property "Value" "2R6F-GP"
			(at -0.0508 -4.8514 270)
			(unlocked yes)
			(layer "F.Fab")
			(hide yes)
			(effects
				(font
					(size 1.016 1.016)
					(thickness 0.1524)
				)
			)
		)
		(property "Device Type" "R1206H26"
			(at 0 -6.3754 270)
			(unlocked yes)
			(layer "F.Fab")
			(hide yes)
			(effects
				(font
					(size 1.016 1.016)
					(thickness 0.1524)
				)
			)
		)
		(duplicate_pad_numbers_are_jumpers no)
		(fp_line
			(start -1.016 2.2352)
			(end -1.016 -2.2352)
			(stroke
				(width 0.1524)
				(type default)
			)
			(layer "F.SilkS")
		)
		(fp_line
			(start 1.016 2.2352)
			(end -1.016 2.2352)
			(stroke
				(width 0.1524)
				(type default)
			)
			(layer "F.SilkS")
		)
		(fp_line
			(start -1.016 -2.2352)
			(end 1.016 -2.2352)
			(stroke
				(width 0.1524)
				(type default)
			)
			(layer "F.SilkS")
		)
		(fp_line
			(start 1.016 -2.2352)
			(end 1.016 2.2352)
			(stroke
				(width 0.1524)
				(type default)
			)
			(layer "F.SilkS")
		)
		(fp_rect
			(start -1.0922 2.3114)
			(end 1.0922 -2.3114)
			(stroke
				(width 0)
				(type default)
			)
			(fill no)
			(layer "F.CrtYd")
		)
		(fp_poly
			(pts
				(xy -1.0922 -2.3114) (xy 1.0922 -2.3114) (xy 1.0922 2.3114) (xy -1.0922 2.3114)
			)
			(stroke
				(width 0)
				(type default)
			)
			(fill no)
			(layer "F.Fab")
		)
		(pad "1" smd rect
			(at 0 -1.397 270)
			(size 1.651 1.27)
			(layers "F.Cu" "F.Mask" "F.Paste")
			(net "P12V_HDD31")
		)
		(pad "2" smd rect
			(at 0 1.397 270)
			(size 1.651 1.27)
			(layers "F.Cu" "F.Mask" "F.Paste")
			(net "12V_PRE_31")
		)
	)
	(footprint ""
		(layer "F.Cu")
		(at 178.0032 -148.717 -90)
		(property "Reference" "C251"
			(at 0 0 270)
			(layer "F.SilkS")
			(hide yes)
			(effects
				(font
					(size 1.27 1.27)
				)
			)
		)
		(property "Value" "SC1U16V3KX-5GP"
			(at 0 -2.8194 270)
			(unlocked yes)
			(layer "F.Fab")
			(hide yes)
			(effects
				(font
					(size 1.016 1.016)
					(thickness 0.1524)
				)
			)
		)
		(property "Device Type" "C603H36"
			(at 0 -4.3434 270)
			(unlocked yes)
			(layer "F.Fab")
			(hide yes)
			(effects
				(font
					(size 1.016 1.016)
					(thickness 0.1524)
				)
			)
		)
		(duplicate_pad_numbers_are_jumpers no)
		(fp_line
			(start 0.508 0)
			(end -0.508 0)
			(stroke
				(width 0.2032)
				(type default)
			)
			(layer "F.SilkS")
		)
		(fp_rect
			(start -0.5842 1.3335)
			(end 0.5842 -1.3335)
			(stroke
				(width 0)
				(type default)
			)
			(fill no)
			(layer "F.CrtYd")
		)
		(fp_rect
			(start -0.5842 1.3335)
			(end 0.5842 -1.3335)
			(stroke
				(width 0)
				(type default)
			)
			(fill no)
			(layer "F.Fab")
		)
		(pad "1" smd custom
			(at 0 -0.762 270)
			(size 0.2159 0.2159)
			(layers "F.Cu" "F.Mask" "F.Paste")
			(net "P5V_HDD17")
			(options
				(clearance outline)
				(anchor circle)
			)
			(primitives
				(gr_poly
					(pts
						(arc
							(start -0.3302 -0.4318)
							(mid -0.402042 -0.402042)
							(end -0.4318 -0.3302)
						)
						(arc
							(start -0.4318 0.3302)
							(mid -0.402042 0.402042)
							(end -0.3302 0.4318)
						)
						(arc
							(start 0.3302 0.4318)
							(mid 0.402042 0.402042)
							(end 0.4318 0.3302)
						)
						(arc
							(start 0.4318 -0.3302)
							(mid 0.402042 -0.402042)
							(end 0.3302 -0.4318)
						)
					)
					(width 0)
					(fill yes)
				)
			)
		)
		(pad "2" smd custom
			(at 0 0.762 270)
			(size 0.2159 0.2159)
			(layers "F.Cu" "F.Mask" "F.Paste")
			(net "GND")
			(options
				(clearance outline)
				(anchor circle)
			)
			(primitives
				(gr_poly
					(pts
						(arc
							(start -0.3302 -0.4318)
							(mid -0.402042 -0.402042)
							(end -0.4318 -0.3302)
						)
						(arc
							(start -0.4318 0.3302)
							(mid -0.402042 0.402042)
							(end -0.3302 0.4318)
						)
						(arc
							(start 0.3302 0.4318)
							(mid 0.402042 0.402042)
							(end 0.4318 0.3302)
						)
						(arc
							(start 0.4318 -0.3302)
							(mid 0.402042 -0.402042)
							(end 0.3302 -0.4318)
						)
					)
					(width 0)
					(fill yes)
				)
			)
		)
	)
	(footprint ""
		(layer "F.Cu")
		(at 49.349914 -180.399944)
		(property "Reference" "LED2"
			(at 0 0 0)
			(layer "F.SilkS")
			(hide yes)
			(effects
				(font
					(size 1.27 1.27)
				)
			)
		)
		(property "Value" "LED-BY-19-GP"
			(at -2.132076 1.414018 0)
			(unlocked yes)
			(layer "F.Fab")
			(hide yes)
			(effects
				(font
					(size 1.016 1.016)
					(thickness 0.1524)
				)
			)
		)
		(property "Device Type" "LED-1615-4PH26"
			(at -2.132076 -0.109982 0)
			(unlocked yes)
			(layer "F.Fab")
			(hide yes)
			(effects
				(font
					(size 1.016 1.016)
					(thickness 0.1524)
				)
			)
		)
		(duplicate_pad_numbers_are_jumpers no)
		(fp_line
			(start -1.2954 0.254)
			(end -1.2954 1.6002)
			(stroke
				(width 0.508)
				(type default)
			)
			(layer "F.SilkS")
		)
		(fp_line
			(start -1.2954 1.6002)
			(end 1.2954 1.6002)
			(stroke
				(width 0.508)
				(type default)
			)
			(layer "F.SilkS")
		)
		(fp_line
			(start -1.1176 -1.4224)
			(end 1.1176 -1.4224)
			(stroke
				(width 0.1524)
				(type default)
			)
			(layer "F.SilkS")
		)
		(fp_line
			(start -1.1176 1.4224)
			(end -1.1176 -1.4224)
			(stroke
				(width 0.1524)
				(type default)
			)
			(layer "F.SilkS")
		)
		(fp_line
			(start 1.1176 -1.4224)
			(end 1.1176 1.4224)
			(stroke
				(width 0.1524)
				(type default)
			)
			(layer "F.SilkS")
		)
		(fp_line
			(start 1.1176 1.4224)
			(end -1.1176 1.4224)
			(stroke
				(width 0.1524)
				(type default)
			)
			(layer "F.SilkS")
		)
		(fp_line
			(start 1.2954 1.6002)
			(end 1.2954 0.254)
			(stroke
				(width 0.508)
				(type default)
			)
			(layer "F.SilkS")
		)
		(fp_rect
			(start -0.7493 0.8001)
			(end 0.7493 -0.8001)
			(stroke
				(width 0)
				(type default)
			)
			(fill no)
			(layer "F.CrtYd")
		)
		(fp_poly
			(pts
				(xy -1.3716 1.6764) (xy -1.3716 -1.6764) (xy 1.3716 -1.6764) (xy 1.3716 0.0635) (xy 0.7493 0.0635)
				(xy 0.7493 -0.8001) (xy -0.7493 -0.8001) (xy -0.7493 0.8001) (xy 0.7493 0.8001) (xy 0.7493 0.0762)
				(xy 1.3716 0.0762) (xy 1.3716 1.6764)
			)
			(stroke
				(width 0)
				(type default)
			)
			(fill no)
			(layer "F.CrtYd")
		)
		(fp_rect
			(start -1.3716 1.6764)
			(end 1.3716 -1.6764)
			(stroke
				(width 0)
				(type default)
			)
			(fill no)
			(layer "F.Fab")
		)
		(pad "1" smd rect
			(at 0.50038 -0.73025)
			(size 0.7112 0.8636)
			(layers "F.Cu" "F.Mask" "F.Paste")
			(net "DRV_ACT_1")
		)
		(pad "2" smd rect
			(at -0.50038 -0.73025)
			(size 0.7112 0.8636)
			(layers "F.Cu" "F.Mask" "F.Paste")
			(net "FLT_HDD1")
		)
		(pad "3" smd rect
			(at 0.50038 0.73025)
			(size 0.7112 0.8636)
			(layers "F.Cu" "F.Mask" "F.Paste")
			(net "DRV_ACT_1_N")
		)
		(pad "4" smd rect
			(at -0.50038 0.73025)
			(size 0.7112 0.8636)
			(layers "F.Cu" "F.Mask" "F.Paste")
			(net "FLT_HDD1_N")
		)
	)
)
